# T6G (Grand Teton) — schematic netlist excerpt (pin names and nets, part order shuffled) for the footprints in the layout excerpt that follows; sources: Cadence DE-HDL packaged netlist, KiCad conversion of 04192023_DAF0TMB3IC0_F0TG_MB_C_brd_V02_OCP.brd

PC254_1  Q_CAP  0.1UF 25V 10% X7R  pkg 0402  page 211 : A = PVDDCR_CPU0_P1_VCCS ; B = GND
PC218  Q_CAP  0.22UF 16V 10% X7R  pkg 0402  page 208 : A = SW_PVDD11_S3_P0_BOOT2_RC ; B = SW_PVDD11_S3_P0_PH2
R6158  Q_RES  0 5% CHIP  pkg 0201LF  page 113 : A = P2E_MB_BMC_RX_DP<0> ; B = P2E_MB_BMC_RX_R2_DP<0>

(kicad_pcb
	(version 20260206)
	(generator "pcbnew")
	(generator_version "10.0")
	(general
		(thickness 1.6)
		(legacy_teardrops no)
	)
	(paper "A4")
	(title_block
		(title "04192023_DAF0TMB3IC0_F0TG_MB_C_brd_V02_OCP.brd")
		(comment 1 "Grand Teton / footprints 4604-4606 of 8354")
	)
	(layers
		(0 "F.Cu" signal "TOP")
		(4 "In1.Cu" signal "GND")
		(6 "In2.Cu" signal "IN1")
		(8 "In3.Cu" signal "GND1")
		(10 "In4.Cu" signal "IN2")
		(12 "In5.Cu" signal "GND2")
		(14 "In6.Cu" signal "IN3")
		(16 "In7.Cu" signal "GND3")
		(18 "In8.Cu" signal "VCC")
		(20 "In9.Cu" signal "VCC1")
		(22 "In10.Cu" signal "GND4")
		(24 "In11.Cu" signal "IN4")
		(26 "In12.Cu" signal "GND5")
		(28 "In13.Cu" signal "IN5")
		(30 "In14.Cu" signal "GND6")
		(32 "In15.Cu" signal "IN6")
		(34 "In16.Cu" signal "GND7")
		(2 "B.Cu" signal "BOTTOM")
		(9 "F.Adhes" user "F.Adhesive")
		(11 "B.Adhes" user "B.Adhesive")
		(13 "F.Paste" user "Package Geometry/Pastemask Top")
		(15 "B.Paste" user "Package Geometry/Pastemask Bottom")
		(5 "F.SilkS" user "Ref Des/Silkscreen Top")
		(7 "B.SilkS" user "Ref Des/Silkscreen Bottom")
		(1 "F.Mask" user "Board Geometry/Soldermask Top")
		(3 "B.Mask" user "Board Geometry/Soldermask Bottom")
		(17 "Dwgs.User" user "User.Drawings")
		(19 "Cmts.User" user "User.Comments")
		(21 "Eco1.User" user "User.Eco1")
		(23 "Eco2.User" user "User.Eco2")
		(25 "Edge.Cuts" user "Board Geometry/Outline")
		(27 "Margin" user)
		(31 "F.CrtYd" user "Package Geometry/Place Bound Top")
		(29 "B.CrtYd" user "Package Geometry/Place Bound Bottom")
		(35 "F.Fab" user "Ref Des/Assembly Top")
		(33 "B.Fab" user "Ref Des/Assembly Bottom")
	)
	(footprint ""
		(layer "F.Cu")
		(at 84.978494 -177.88636 -90)
		(property "Reference" "PC254_1"
			(at 0 0 270)
			(layer "F.SilkS")
			(hide yes)
			(effects
				(font
					(size 1.27 1.27)
				)
			)
		)
		(property "Value" ""
			(at 0 0 270)
			(layer "F.Fab")
			(effects
				(font
					(size 1.27 1.27)
				)
			)
		)
		(duplicate_pad_numbers_are_jumpers no)
		(fp_line
			(start -0.7874 0.4064)
			(end -0.7874 -0.4064)
			(stroke
				(width 0.1524)
				(type default)
			)
			(layer "F.SilkS")
		)
		(fp_line
			(start 0.7874 0.4064)
			(end -0.7874 0.4064)
			(stroke
				(width 0.1524)
				(type default)
			)
			(layer "F.SilkS")
		)
		(fp_line
			(start -0.7874 -0.4064)
			(end 0.7874 -0.4064)
			(stroke
				(width 0.1524)
				(type default)
			)
			(layer "F.SilkS")
		)
		(fp_line
			(start 0.7874 -0.4064)
			(end 0.7874 0.4064)
			(stroke
				(width 0.1524)
				(type default)
			)
			(layer "F.SilkS")
		)
		(fp_line
			(start -0.67945 0.3048)
			(end -0.67945 -0.305054)
			(stroke
				(width 0.1)
				(type default)
			)
			(layer "F.Fab")
		)
		(fp_line
			(start -0.12065 0.3048)
			(end -0.67945 0.3048)
			(stroke
				(width 0.1)
				(type default)
			)
			(layer "F.Fab")
		)
		(fp_line
			(start 0.120396 0.3048)
			(end 0.120396 0.2794)
			(stroke
				(width 0.1)
				(type default)
			)
			(layer "F.Fab")
		)
		(fp_line
			(start 0.67945 0.3048)
			(end 0.120396 0.3048)
			(stroke
				(width 0.1)
				(type default)
			)
			(layer "F.Fab")
		)
		(fp_line
			(start -0.12065 0.2794)
			(end -0.12065 0.3048)
			(stroke
				(width 0.1)
				(type default)
			)
			(layer "F.Fab")
		)
		(fp_line
			(start 0.120396 0.2794)
			(end -0.12065 0.2794)
			(stroke
				(width 0.1)
				(type default)
			)
			(layer "F.Fab")
		)
		(fp_line
			(start -0.12065 -0.2794)
			(end 0.12065 -0.2794)
			(stroke
				(width 0.1)
				(type default)
			)
			(layer "F.Fab")
		)
		(fp_line
			(start 0.12065 -0.2794)
			(end 0.12065 -0.3048)
			(stroke
				(width 0.1)
				(type default)
			)
			(layer "F.Fab")
		)
		(fp_line
			(start 0.12065 -0.3048)
			(end 0.67945 -0.3048)
			(stroke
				(width 0.1)
				(type default)
			)
			(layer "F.Fab")
		)
		(fp_line
			(start 0.67945 -0.3048)
			(end 0.67945 0.3048)
			(stroke
				(width 0.1)
				(type default)
			)
			(layer "F.Fab")
		)
		(fp_line
			(start -0.67945 -0.305054)
			(end -0.12065 -0.305054)
			(stroke
				(width 0.1)
				(type default)
			)
			(layer "F.Fab")
		)
		(fp_line
			(start -0.12065 -0.305054)
			(end -0.12065 -0.2794)
			(stroke
				(width 0.1)
				(type default)
			)
			(layer "F.Fab")
		)
		(pad "1" smd circle
			(at -0.40005 0 270)
			(size 0 0)
			(layers "F.Cu" "F.Mask" "F.Paste")
			(net "PVDDCR_CPU0_P1_VCCS")
		)
		(pad "2" smd circle
			(at 0.40005 0 270)
			(size 0 0)
			(layers "F.Cu" "F.Mask" "F.Paste")
			(net "GND")
		)
	)
	(footprint ""
		(layer "F.Cu")
		(at 433.756562 -355.743764 -90)
		(property "Reference" "PC218"
			(at 0 0 270)
			(layer "F.SilkS")
			(hide yes)
			(effects
				(font
					(size 1.27 1.27)
				)
			)
		)
		(property "Value" ""
			(at 0 0 270)
			(layer "F.Fab")
			(effects
				(font
					(size 1.27 1.27)
				)
			)
		)
		(duplicate_pad_numbers_are_jumpers no)
		(fp_line
			(start -0.7874 0.4064)
			(end -0.7874 -0.4064)
			(stroke
				(width 0.1524)
				(type default)
			)
			(layer "F.SilkS")
		)
		(fp_line
			(start 0.7874 0.4064)
			(end -0.7874 0.4064)
			(stroke
				(width 0.1524)
				(type default)
			)
			(layer "F.SilkS")
		)
		(fp_line
			(start -0.7874 -0.4064)
			(end 0.7874 -0.4064)
			(stroke
				(width 0.1524)
				(type default)
			)
			(layer "F.SilkS")
		)
		(fp_line
			(start 0.7874 -0.4064)
			(end 0.7874 0.4064)
			(stroke
				(width 0.1524)
				(type default)
			)
			(layer "F.SilkS")
		)
		(fp_line
			(start -0.67945 0.3048)
			(end -0.67945 -0.305054)
			(stroke
				(width 0.1)
				(type default)
			)
			(layer "F.Fab")
		)
		(fp_line
			(start -0.12065 0.3048)
			(end -0.67945 0.3048)
			(stroke
				(width 0.1)
				(type default)
			)
			(layer "F.Fab")
		)
		(fp_line
			(start 0.120396 0.3048)
			(end 0.120396 0.2794)
			(stroke
				(width 0.1)
				(type default)
			)
			(layer "F.Fab")
		)
		(fp_line
			(start 0.67945 0.3048)
			(end 0.120396 0.3048)
			(stroke
				(width 0.1)
				(type default)
			)
			(layer "F.Fab")
		)
		(fp_line
			(start -0.12065 0.2794)
			(end -0.12065 0.3048)
			(stroke
				(width 0.1)
				(type default)
			)
			(layer "F.Fab")
		)
		(fp_line
			(start 0.120396 0.2794)
			(end -0.12065 0.2794)
			(stroke
				(width 0.1)
				(type default)
			)
			(layer "F.Fab")
		)
		(fp_line
			(start -0.12065 -0.2794)
			(end 0.12065 -0.2794)
			(stroke
				(width 0.1)
				(type default)
			)
			(layer "F.Fab")
		)
		(fp_line
			(start 0.12065 -0.2794)
			(end 0.12065 -0.3048)
			(stroke
				(width 0.1)
				(type default)
			)
			(layer "F.Fab")
		)
		(fp_line
			(start 0.12065 -0.3048)
			(end 0.67945 -0.3048)
			(stroke
				(width 0.1)
				(type default)
			)
			(layer "F.Fab")
		)
		(fp_line
			(start 0.67945 -0.3048)
			(end 0.67945 0.3048)
			(stroke
				(width 0.1)
				(type default)
			)
			(layer "F.Fab")
		)
		(fp_line
			(start -0.67945 -0.305054)
			(end -0.12065 -0.305054)
			(stroke
				(width 0.1)
				(type default)
			)
			(layer "F.Fab")
		)
		(fp_line
			(start -0.12065 -0.305054)
			(end -0.12065 -0.2794)
			(stroke
				(width 0.1)
				(type default)
			)
			(layer "F.Fab")
		)
		(pad "1" smd circle
			(at -0.40005 0 270)
			(size 0 0)
			(layers "F.Cu" "F.Mask" "F.Paste")
			(net "SW_PVDD11_S3_P0_BOOT2_RC")
		)
		(pad "2" smd circle
			(at 0.40005 0 270)
			(size 0 0)
			(layers "F.Cu" "F.Mask" "F.Paste")
			(net "SW_PVDD11_S3_P0_PH2")
		)
	)
	(footprint ""
		(layer "F.Cu")
		(at 27.487626 -428.755302 180)
		(property "Reference" "R6158"
			(at 0 0 180)
			(layer "F.SilkS")
			(hide yes)
			(effects
				(font
					(size 1.27 1.27)
				)
			)
		)
		(property "Value" ""
			(at 0 0 180)
			(layer "F.Fab")
			(effects
				(font
					(size 1.27 1.27)
				)
			)
		)
		(duplicate_pad_numbers_are_jumpers no)
		(fp_line
			(start 0.32512 0.175006)
			(end -0.32512 0.175006)
			(stroke
				(width 0.1)
				(type default)
			)
			(layer "F.Fab")
		)
		(fp_line
			(start 0.32512 -0.175006)
			(end 0.32512 0.175006)
			(stroke
				(width 0.1)
				(type default)
			)
			(layer "F.Fab")
		)
		(fp_line
			(start -0.32512 0.175006)
			(end -0.32512 -0.175006)
			(stroke
				(width 0.1)
				(type default)
			)
			(layer "F.Fab")
		)
		(fp_line
			(start -0.32512 -0.175006)
			(end 0.32512 -0.175006)
			(stroke
				(width 0.1)
				(type default)
			)
			(layer "F.Fab")
		)
		(pad "1" smd rect
			(at -0.2667 0 180)
			(size 0.3048 0.381)
			(layers "F.Cu" "F.Mask" "F.Paste")
			(net "P2E_MB_BMC_RX_DP<0>")
		)
		(pad "2" smd rect
			(at 0.2667 0)
			(size 0.3048 0.381)
			(layers "F.Cu" "F.Mask" "F.Paste")
			(net "P2E_MB_BMC_RX_R2_DP<0>")
		)
	)
)
